(kicad_pcb
	(version 20260206)
	(generator "pcbnew")
	(generator_version "10.0")
	(general
		(thickness 1.6)
		(legacy_teardrops no)
	)
	(paper "A4")
	(title_block
		(title "baseboard — 13948-1b.1110WZS1818.brd")
		(comment 1 "Honey Badger (Wiwynn) / footprint 1078 of 2523 (SU1), pads 233-347 of 672")
	)
	(layers
		(0 "F.Cu" signal "TOP")
		(4 "In1.Cu" signal "L2GND")
		(6 "In2.Cu" signal "L3")
		(8 "In3.Cu" signal "L4VCC")
		(10 "In4.Cu" signal "L5VCC")
		(12 "In5.Cu" signal "L6")
		(14 "In6.Cu" signal "L7GND")
		(2 "B.Cu" signal "BOTTOM")
		(9 "F.Adhes" user "F.Adhesive")
		(11 "B.Adhes" user "B.Adhesive")
		(13 "F.Paste" user "Package Geometry/Pastemask Top")
		(15 "B.Paste" user "Package Geometry/Pastemask Bottom")
		(5 "F.SilkS" user "Ref Des/Silkscreen Top")
		(7 "B.SilkS" user "Ref Des/Silkscreen Bottom")
		(1 "F.Mask" user "Board Geometry/Soldermask Top")
		(3 "B.Mask" user "Board Geometry/Soldermask Bottom")
		(17 "Dwgs.User" user "User.Drawings")
		(19 "Cmts.User" user "User.Comments")
		(21 "Eco1.User" user "User.Eco1")
		(23 "Eco2.User" user "User.Eco2")
		(25 "Edge.Cuts" user "Board Geometry/Outline")
		(27 "Margin" user)
		(31 "F.CrtYd" user "Package Geometry/Place Bound Top")
		(29 "B.CrtYd" user "Package Geometry/Place Bound Bottom")
		(35 "F.Fab" user "Ref Des/Assembly Top")
		(33 "B.Fab" user "Ref Des/Assembly Bottom")
	)
	(footprint ""
		(layer "F.Cu")
		(at 114.84991 -94.84995 90)
		(property "Reference" "SU1"
			(at 0 0 90)
			(layer "F.SilkS")
			(hide yes)
			(effects
				(font
					(size 1.27 1.27)
				)
			)
		)
		(property "Value" "SAS3X24RLC1-DB-500021106-GP"
			(at -21.4503 -7.4168 90)
			(unlocked yes)
			(layer "F.Fab")
			(hide yes)
			(effects
				(font
					(size 1.016 1.016)
					(thickness 0.1524)
				)
			)
		)
		(property "Device Type" "BGA672C27H83"
			(at -21.4503 -8.9408 90)
			(unlocked yes)
			(layer "F.Fab")
			(hide yes)
			(effects
				(font
					(size 1.016 1.016)
					(thickness 0.1524)
				)
			)
		)
		(duplicate_pad_numbers_are_jumpers no)
		(pad "D3" smd circle
			(at -10.500106 -9.500108 90)
			(size 0.4572 0.4572)
			(layers "F.Cu" "F.Mask" "F.Paste")
			(net "GND")
		)
		(pad "D4" smd circle
			(at -9.500108 -9.500108 90)
			(size 0.4572 0.4572)
			(layers "F.Cu" "F.Mask" "F.Paste")
			(net "P1V8_E")
		)
		(pad "D5" smd circle
			(at -8.50011 -9.500108 90)
			(size 0.4572 0.4572)
			(layers "F.Cu" "F.Mask" "F.Paste")
			(net "EXP_RESET_N")
		)
		(pad "D6" smd circle
			(at -7.500112 -9.500108 90)
			(size 0.4572 0.4572)
			(layers "F.Cu" "F.Mask" "F.Paste")
			(net "P1V8_E")
		)
		(pad "D7" smd circle
			(at -6.500114 -9.500108 90)
			(size 0.4572 0.4572)
			(layers "F.Cu" "F.Mask" "F.Paste")
			(net "Net_1127")
		)
		(pad "D8" smd circle
			(at -5.500116 -9.500108 90)
			(size 0.4572 0.4572)
			(layers "F.Cu" "F.Mask" "F.Paste")
			(net "P1V8_E")
		)
		(pad "D9" smd circle
			(at -4.500118 -9.500108 90)
			(size 0.4572 0.4572)
			(layers "F.Cu" "F.Mask" "F.Paste")
			(net "XM_DATA2")
		)
		(pad "D10" smd circle
			(at -3.50012 -9.500108 90)
			(size 0.4572 0.4572)
			(layers "F.Cu" "F.Mask" "F.Paste")
			(net "P1V8_E")
		)
		(pad "D11" smd circle
			(at -2.500122 -9.500108 90)
			(size 0.4572 0.4572)
			(layers "F.Cu" "F.Mask" "F.Paste")
			(net "EXP_XM_ADDR_5")
		)
		(pad "D12" smd circle
			(at -1.500124 -9.500108 90)
			(size 0.4572 0.4572)
			(layers "F.Cu" "F.Mask" "F.Paste")
			(net "P1V8_E")
		)
		(pad "D13" smd circle
			(at -0.500126 -9.500108 90)
			(size 0.4572 0.4572)
			(layers "F.Cu" "F.Mask" "F.Paste")
			(net "EXP_XM_ADDR_16")
		)
		(pad "D14" smd circle
			(at 0.500126 -9.500108 90)
			(size 0.4572 0.4572)
			(layers "F.Cu" "F.Mask" "F.Paste")
			(net "P1V8_E")
		)
		(pad "D15" smd circle
			(at 1.500124 -9.500108 90)
			(size 0.4572 0.4572)
			(layers "F.Cu" "F.Mask" "F.Paste")
			(net "EXP_PWM_OUT0")
		)
		(pad "D16" smd circle
			(at 2.500122 -9.500108 90)
			(size 0.4572 0.4572)
			(layers "F.Cu" "F.Mask" "F.Paste")
			(net "P1V8_E")
		)
		(pad "D17" smd circle
			(at 3.50012 -9.500108 90)
			(size 0.4572 0.4572)
			(layers "F.Cu" "F.Mask" "F.Paste")
			(net "EXP_GPIO_8")
		)
		(pad "D18" smd circle
			(at 4.500118 -9.500108 90)
			(size 0.4572 0.4572)
			(layers "F.Cu" "F.Mask" "F.Paste")
			(net "P1V8_E")
		)
		(pad "D19" smd circle
			(at 5.500116 -9.500108 90)
			(size 0.4572 0.4572)
			(layers "F.Cu" "F.Mask" "F.Paste")
			(net "PHY_CLK")
		)
		(pad "D20" smd circle
			(at 6.500114 -9.500108 90)
			(size 0.4572 0.4572)
			(layers "F.Cu" "F.Mask" "F.Paste")
			(net "P1V8_E")
		)
		(pad "D21" smd circle
			(at 7.500112 -9.500108 90)
			(size 0.4572 0.4572)
			(layers "F.Cu" "F.Mask" "F.Paste")
			(net "UART_CTS")
		)
		(pad "D22" smd circle
			(at 8.50011 -9.500108 90)
			(size 0.4572 0.4572)
			(layers "F.Cu" "F.Mask" "F.Paste")
			(net "P1V8_E")
		)
		(pad "D23" smd circle
			(at 9.500108 -9.500108 90)
			(size 0.4572 0.4572)
			(layers "F.Cu" "F.Mask" "F.Paste")
			(net "EXP_I2C_SDA_1")
		)
		(pad "D24" smd circle
			(at 10.500106 -9.500108 90)
			(size 0.4572 0.4572)
			(layers "F.Cu" "F.Mask" "F.Paste")
			(net "P1V8_E")
		)
		(pad "D25" smd circle
			(at 11.500104 -9.500108 90)
			(size 0.4572 0.4572)
			(layers "F.Cu" "F.Mask" "F.Paste")
			(net "EXP_I2C_SCL_1")
		)
		(pad "D26" smd circle
			(at 12.500102 -9.500108 90)
			(size 0.4572 0.4572)
			(layers "F.Cu" "F.Mask" "F.Paste")
			(net "P1V8_E")
		)
		(pad "E1" smd circle
			(at -12.500102 -8.50011 90)
			(size 0.4572 0.4572)
			(layers "F.Cu" "F.Mask" "F.Paste")
			(net "SAS_HDD_LED1")
		)
		(pad "E2" smd circle
			(at -11.500104 -8.50011 90)
			(size 0.4572 0.4572)
			(layers "F.Cu" "F.Mask" "F.Paste")
			(net "SAS_HDD_LED0")
		)
		(pad "E3" smd circle
			(at -10.500106 -8.50011 90)
			(size 0.4572 0.4572)
			(layers "F.Cu" "F.Mask" "F.Paste")
			(net "EXP_BLINK_IN")
		)
		(pad "E4" smd circle
			(at -9.500108 -8.50011 90)
			(size 0.4572 0.4572)
			(layers "F.Cu" "F.Mask" "F.Paste")
			(net "JTAG_EXP_TDO_R")
		)
		(pad "E5" smd circle
			(at -8.50011 -8.50011 90)
			(size 0.4572 0.4572)
			(layers "F.Cu" "F.Mask" "F.Paste")
			(net "EXP_CPU_MODE_1")
		)
		(pad "E6" smd circle
			(at -7.500112 -8.50011 90)
			(size 0.4572 0.4572)
			(layers "F.Cu" "F.Mask" "F.Paste")
			(net "EXP_CLK_SEL1")
		)
		(pad "E7" smd circle
			(at -6.500114 -8.50011 90)
			(size 0.4572 0.4572)
			(layers "F.Cu" "F.Mask" "F.Paste")
			(net "Net_1131")
		)
		(pad "E8" smd circle
			(at -5.500116 -8.50011 90)
			(size 0.4572 0.4572)
			(layers "F.Cu" "F.Mask" "F.Paste")
			(net "Net_1130")
		)
		(pad "E9" smd circle
			(at -4.500118 -8.50011 90)
			(size 0.4572 0.4572)
			(layers "F.Cu" "F.Mask" "F.Paste")
			(net "P1V8_E")
		)
		(pad "E10" smd circle
			(at -3.50012 -8.50011 90)
			(size 0.4572 0.4572)
			(layers "F.Cu" "F.Mask" "F.Paste")
			(net "XM_DATA12")
		)
		(pad "E11" smd circle
			(at -2.500122 -8.50011 90)
			(size 0.4572 0.4572)
			(layers "F.Cu" "F.Mask" "F.Paste")
			(net "EXP_XM_ADDR_8")
		)
		(pad "E12" smd circle
			(at -1.500124 -8.50011 90)
			(size 0.4572 0.4572)
			(layers "F.Cu" "F.Mask" "F.Paste")
			(net "EXP_XM_ADDR_23")
		)
		(pad "E13" smd circle
			(at -0.500126 -8.50011 90)
			(size 0.4572 0.4572)
			(layers "F.Cu" "F.Mask" "F.Paste")
			(net "EXP_XM_ADDR_17")
		)
		(pad "E14" smd circle
			(at 0.500126 -8.50011 90)
			(size 0.4572 0.4572)
			(layers "F.Cu" "F.Mask" "F.Paste")
			(net "EXP_XM_ADDR_11")
		)
		(pad "E15" smd circle
			(at 1.500124 -8.50011 90)
			(size 0.4572 0.4572)
			(layers "F.Cu" "F.Mask" "F.Paste")
			(net "EXP_TACH_IN2")
		)
		(pad "E16" smd circle
			(at 2.500122 -8.50011 90)
			(size 0.4572 0.4572)
			(layers "F.Cu" "F.Mask" "F.Paste")
			(net "EXP_GPIO_10")
		)
		(pad "E17" smd circle
			(at 3.50012 -8.50011 90)
			(size 0.4572 0.4572)
			(layers "F.Cu" "F.Mask" "F.Paste")
			(net "EXP_GPIO_3")
		)
		(pad "E18" smd circle
			(at 4.500118 -8.50011 90)
			(size 0.4572 0.4572)
			(layers "F.Cu" "F.Mask" "F.Paste")
			(net "SDB_R_RX")
		)
		(pad "E19" smd circle
			(at 5.500116 -8.50011 90)
			(size 0.4572 0.4572)
			(layers "F.Cu" "F.Mask" "F.Paste")
			(net "ICE_TDO")
		)
		(pad "E20" smd circle
			(at 6.500114 -8.50011 90)
			(size 0.4572 0.4572)
			(layers "F.Cu" "F.Mask" "F.Paste")
			(net "SIO_LOAD_IN")
		)
		(pad "E21" smd circle
			(at 7.500112 -8.50011 90)
			(size 0.4572 0.4572)
			(layers "F.Cu" "F.Mask" "F.Paste")
			(net "GND")
		)
		(pad "E22" smd circle
			(at 8.50011 -8.50011 90)
			(size 0.4572 0.4572)
			(layers "F.Cu" "F.Mask" "F.Paste")
			(net "GND")
		)
		(pad "E23" smd circle
			(at 9.500108 -8.50011 90)
			(size 0.4572 0.4572)
			(layers "F.Cu" "F.Mask" "F.Paste")
			(net "EXP_SCL_0")
		)
		(pad "E24" smd circle
			(at 10.500106 -8.50011 90)
			(size 0.4572 0.4572)
			(layers "F.Cu" "F.Mask" "F.Paste")
			(net "GND")
		)
		(pad "E25" smd circle
			(at 11.500104 -8.50011 90)
			(size 0.4572 0.4572)
			(layers "F.Cu" "F.Mask" "F.Paste")
			(net "GND")
		)
		(pad "E26" smd circle
			(at 12.500102 -8.50011 90)
			(size 0.4572 0.4572)
			(layers "F.Cu" "F.Mask" "F.Paste")
			(net "GND")
		)
		(pad "F1" smd circle
			(at -12.500102 -7.500112 90)
			(size 0.4572 0.4572)
			(layers "F.Cu" "F.Mask" "F.Paste")
			(net "SAS_HDD_LED4")
		)
		(pad "F2" smd circle
			(at -11.500104 -7.500112 90)
			(size 0.4572 0.4572)
			(layers "F.Cu" "F.Mask" "F.Paste")
			(net "SAS_HDD_LED2")
		)
		(pad "F3" smd circle
			(at -10.500106 -7.500112 90)
			(size 0.4572 0.4572)
			(layers "F.Cu" "F.Mask" "F.Paste")
			(net "GND")
		)
		(pad "F4" smd circle
			(at -9.500108 -7.500112 90)
			(size 0.4572 0.4572)
			(layers "F.Cu" "F.Mask" "F.Paste")
			(net "P1V8_E")
		)
		(pad "F5" smd circle
			(at -8.50011 -7.500112 90)
			(size 0.4572 0.4572)
			(layers "F.Cu" "F.Mask" "F.Paste")
			(net "JTAG_EXP_TCK")
		)
		(pad "F6" smd circle
			(at -7.500112 -7.500112 90)
			(size 0.4572 0.4572)
			(layers "F.Cu" "F.Mask" "F.Paste")
			(net "TMUX_EN")
		)
		(pad "F7" smd circle
			(at -6.500114 -7.500112 90)
			(size 0.4572 0.4572)
			(layers "F.Cu" "F.Mask" "F.Paste")
			(net "LSI_T_N")
		)
		(pad "F8" smd circle
			(at -5.500116 -7.500112 90)
			(size 0.4572 0.4572)
			(layers "F.Cu" "F.Mask" "F.Paste")
			(net "EXP_CPU_MODE_0")
		)
		(pad "F9" smd circle
			(at -4.500118 -7.500112 90)
			(size 0.4572 0.4572)
			(layers "F.Cu" "F.Mask" "F.Paste")
			(net "EXP_XM_NOR_CS_N")
		)
		(pad "F10" smd circle
			(at -3.50012 -7.500112 90)
			(size 0.4572 0.4572)
			(layers "F.Cu" "F.Mask" "F.Paste")
			(net "XM_DATA4")
		)
		(pad "F11" smd circle
			(at -2.500122 -7.500112 90)
			(size 0.4572 0.4572)
			(layers "F.Cu" "F.Mask" "F.Paste")
			(net "XM_DATA13")
		)
		(pad "F12" smd circle
			(at -1.500124 -7.500112 90)
			(size 0.4572 0.4572)
			(layers "F.Cu" "F.Mask" "F.Paste")
			(net "XM_DATA0")
		)
		(pad "F13" smd circle
			(at -0.500126 -7.500112 90)
			(size 0.4572 0.4572)
			(layers "F.Cu" "F.Mask" "F.Paste")
			(net "EXP_XM_ADDR_2")
		)
		(pad "F14" smd circle
			(at 0.500126 -7.500112 90)
			(size 0.4572 0.4572)
			(layers "F.Cu" "F.Mask" "F.Paste")
			(net "EXP_XM_ADDR_15")
		)
		(pad "F15" smd circle
			(at 1.500124 -7.500112 90)
			(size 0.4572 0.4572)
			(layers "F.Cu" "F.Mask" "F.Paste")
			(net "EXP_FW_DET_BOARD_VER_1")
		)
		(pad "F16" smd circle
			(at 2.500122 -7.500112 90)
			(size 0.4572 0.4572)
			(layers "F.Cu" "F.Mask" "F.Paste")
			(net "LSI_EFUSE")
		)
		(pad "F17" smd circle
			(at 3.50012 -7.500112 90)
			(size 0.4572 0.4572)
			(layers "F.Cu" "F.Mask" "F.Paste")
			(net "ICE_TCK")
		)
		(pad "F18" smd circle
			(at 4.500118 -7.500112 90)
			(size 0.4572 0.4572)
			(layers "F.Cu" "F.Mask" "F.Paste")
			(net "ICE_TDI")
		)
		(pad "F19" smd circle
			(at 5.500116 -7.500112 90)
			(size 0.4572 0.4572)
			(layers "F.Cu" "F.Mask" "F.Paste")
			(net "SIO_D_IN")
		)
		(pad "F20" smd circle
			(at 6.500114 -7.500112 90)
			(size 0.4572 0.4572)
			(layers "F.Cu" "F.Mask" "F.Paste")
			(net "GND")
		)
		(pad "F21" smd circle
			(at 7.500112 -7.500112 90)
			(size 0.4572 0.4572)
			(layers "F.Cu" "F.Mask" "F.Paste")
			(net "SAS_GF_EXP_RX_DN15")
		)
		(pad "F22" smd circle
			(at 8.50011 -7.500112 90)
			(size 0.4572 0.4572)
			(layers "F.Cu" "F.Mask" "F.Paste")
			(net "SAS_GF_EXP_RX_DP15")
		)
		(pad "F23" smd circle
			(at 9.500108 -7.500112 90)
			(size 0.4572 0.4572)
			(layers "F.Cu" "F.Mask" "F.Paste")
			(net "GND")
		)
		(pad "F24" smd circle
			(at 10.500106 -7.500112 90)
			(size 0.4572 0.4572)
			(layers "F.Cu" "F.Mask" "F.Paste")
			(net "GB_VDDA")
		)
		(pad "F25" smd circle
			(at 11.500104 -7.500112 90)
			(size 0.4572 0.4572)
			(layers "F.Cu" "F.Mask" "F.Paste")
			(net "SAS_HDD_TX11_N")
		)
		(pad "F26" smd circle
			(at 12.500102 -7.500112 90)
			(size 0.4572 0.4572)
			(layers "F.Cu" "F.Mask" "F.Paste")
			(net "SAS_HDD_TX11_P")
		)
		(pad "G1" smd circle
			(at -12.500102 -6.500114 90)
			(size 0.4572 0.4572)
			(layers "F.Cu" "F.Mask" "F.Paste")
			(net "SAS_HDD_LED10")
		)
		(pad "G2" smd circle
			(at -11.500104 -6.500114 90)
			(size 0.4572 0.4572)
			(layers "F.Cu" "F.Mask" "F.Paste")
			(net "SAS_HDD_LED6")
		)
		(pad "G3" smd circle
			(at -10.500106 -6.500114 90)
			(size 0.4572 0.4572)
			(layers "F.Cu" "F.Mask" "F.Paste")
			(net "SAS_HDD_LED5")
		)
		(pad "G4" smd circle
			(at -9.500108 -6.500114 90)
			(size 0.4572 0.4572)
			(layers "F.Cu" "F.Mask" "F.Paste")
			(net "SXP_ACTIVE_2")
		)
		(pad "G5" smd circle
			(at -8.50011 -6.500114 90)
			(size 0.4572 0.4572)
			(layers "F.Cu" "F.Mask" "F.Paste")
			(net "SXP_ACTIVE_0")
		)
		(pad "G6" smd circle
			(at -7.500112 -6.500114 90)
			(size 0.4572 0.4572)
			(layers "F.Cu" "F.Mask" "F.Paste")
			(net "SAS_HDD_LED3")
		)
		(pad "G7" smd circle
			(at -6.500114 -6.500114 90)
			(size 0.4572 0.4572)
			(layers "F.Cu" "F.Mask" "F.Paste")
			(net "GND")
		)
		(pad "G8" smd circle
			(at -5.500116 -6.500114 90)
			(size 0.4572 0.4572)
			(layers "F.Cu" "F.Mask" "F.Paste")
			(net "LSI_SCAN_ENABLE")
		)
		(pad "G9" smd circle
			(at -4.500118 -6.500114 90)
			(size 0.4572 0.4572)
			(layers "F.Cu" "F.Mask" "F.Paste")
			(net "GND")
		)
		(pad "G10" smd circle
			(at -3.50012 -6.500114 90)
			(size 0.4572 0.4572)
			(layers "F.Cu" "F.Mask" "F.Paste")
			(net "XM_DATA9")
		)
		(pad "G11" smd circle
			(at -2.500122 -6.500114 90)
			(size 0.4572 0.4572)
			(layers "F.Cu" "F.Mask" "F.Paste")
			(net "GND")
		)
		(pad "G12" smd circle
			(at -1.500124 -6.500114 90)
			(size 0.4572 0.4572)
			(layers "F.Cu" "F.Mask" "F.Paste")
			(net "EXP_XM_ADDR_6")
		)
		(pad "G13" smd circle
			(at -0.500126 -6.500114 90)
			(size 0.4572 0.4572)
			(layers "F.Cu" "F.Mask" "F.Paste")
			(net "GND")
		)
		(pad "G14" smd circle
			(at 0.500126 -6.500114 90)
			(size 0.4572 0.4572)
			(layers "F.Cu" "F.Mask" "F.Paste")
			(net "EXP_XM_ADDR_10")
		)
		(pad "G15" smd circle
			(at 1.500124 -6.500114 90)
			(size 0.4572 0.4572)
			(layers "F.Cu" "F.Mask" "F.Paste")
			(net "EXP_GPIO_9")
		)
		(pad "G16" smd circle
			(at 2.500122 -6.500114 90)
			(size 0.4572 0.4572)
			(layers "F.Cu" "F.Mask" "F.Paste")
			(net "GND")
		)
		(pad "G17" smd circle
			(at 3.50012 -6.500114 90)
			(size 0.4572 0.4572)
			(layers "F.Cu" "F.Mask" "F.Paste")
			(net "SIO_LOAD_OUT")
		)
		(pad "G18" smd circle
			(at 4.500118 -6.500114 90)
			(size 0.4572 0.4572)
			(layers "F.Cu" "F.Mask" "F.Paste")
			(net "GND")
		)
		(pad "G19" smd circle
			(at 5.500116 -6.500114 90)
			(size 0.4572 0.4572)
			(layers "F.Cu" "F.Mask" "F.Paste")
			(net "EXP_I2C_SDA_4")
		)
		(pad "G20" smd circle
			(at 6.500114 -6.500114 90)
			(size 0.4572 0.4572)
			(layers "F.Cu" "F.Mask" "F.Paste")
			(net "GND")
		)
		(pad "G21" smd circle
			(at 7.500112 -6.500114 90)
			(size 0.4572 0.4572)
			(layers "F.Cu" "F.Mask" "F.Paste")
			(net "SAS_GF_EXP_RX_DN14")
		)
		(pad "G22" smd circle
			(at 8.50011 -6.500114 90)
			(size 0.4572 0.4572)
			(layers "F.Cu" "F.Mask" "F.Paste")
			(net "SAS_GF_EXP_RX_DP14")
		)
		(pad "G23" smd circle
			(at 9.500108 -6.500114 90)
			(size 0.4572 0.4572)
			(layers "F.Cu" "F.Mask" "F.Paste")
			(net "GB_VDDA")
		)
		(pad "G24" smd circle
			(at 10.500106 -6.500114 90)
			(size 0.4572 0.4572)
			(layers "F.Cu" "F.Mask" "F.Paste")
			(net "SAS_HDD_TX10_N")
		)
		(pad "G25" smd circle
			(at 11.500104 -6.500114 90)
			(size 0.4572 0.4572)
			(layers "F.Cu" "F.Mask" "F.Paste")
			(net "SAS_HDD_TX10_P")
		)
		(pad "G26" smd circle
			(at 12.500102 -6.500114 90)
			(size 0.4572 0.4572)
			(layers "F.Cu" "F.Mask" "F.Paste")
			(net "GND")
		)
		(pad "H1" smd circle
			(at -12.500102 -5.500116 90)
			(size 0.4572 0.4572)
			(layers "F.Cu" "F.Mask" "F.Paste")
			(net "GND")
		)
		(pad "H2" smd circle
			(at -11.500104 -5.500116 90)
			(size 0.4572 0.4572)
			(layers "F.Cu" "F.Mask" "F.Paste")
			(net "SAS_HDD_LED9")
		)
		(pad "H3" smd circle
			(at -10.500106 -5.500116 90)
			(size 0.4572 0.4572)
			(layers "F.Cu" "F.Mask" "F.Paste")
			(net "GND")
		)
		(pad "H4" smd circle
			(at -9.500108 -5.500116 90)
			(size 0.4572 0.4572)
			(layers "F.Cu" "F.Mask" "F.Paste")
			(net "P1V8_E")
		)
		(pad "H5" smd circle
			(at -8.50011 -5.500116 90)
			(size 0.4572 0.4572)
			(layers "F.Cu" "F.Mask" "F.Paste")
			(net "SAS_HDD_LED7")
		)
		(pad "H6" smd circle
			(at -7.500112 -5.500116 90)
			(size 0.4572 0.4572)
			(layers "F.Cu" "F.Mask" "F.Paste")
			(net "SAS_HDD_LED8")
		)
		(pad "H7" smd circle
			(at -6.500114 -5.500116 90)
			(size 0.4572 0.4572)
			(layers "F.Cu" "F.Mask" "F.Paste")
			(net "P1V8_E")
		)
		(pad "H8" smd circle
			(at -5.500116 -5.500116 90)
			(size 0.4572 0.4572)
			(layers "F.Cu" "F.Mask" "F.Paste")
			(net "SXP_ACTIVE_1")
		)
		(pad "H9" smd circle
			(at -4.500118 -5.500116 90)
			(size 0.4572 0.4572)
			(layers "F.Cu" "F.Mask" "F.Paste")
			(net "P1V8_E")
		)
		(pad "H10" smd circle
			(at -3.50012 -5.500116 90)
			(size 0.4572 0.4572)
			(layers "F.Cu" "F.Mask" "F.Paste")
			(net "EXP_CLK_SEL0")
		)
		(pad "H11" smd circle
			(at -2.500122 -5.500116 90)
			(size 0.4572 0.4572)
			(layers "F.Cu" "F.Mask" "F.Paste")
			(net "P1V8_E")
		)
		(pad "H12" smd circle
			(at -1.500124 -5.500116 90)
			(size 0.4572 0.4572)
			(layers "F.Cu" "F.Mask" "F.Paste")
			(net "EXP_XM_ADDR_24")
		)
		(pad "H13" smd circle
			(at -0.500126 -5.500116 90)
			(size 0.4572 0.4572)
			(layers "F.Cu" "F.Mask" "F.Paste")
			(net "P1V8_E")
		)
	)
)
